(kicad_pcb
	(version 20260206)
	(generator "pcbnew")
	(generator_version "10.0")
	(general
		(thickness 1.6)
		(legacy_teardrops no)
	)
	(paper "A4")
	(title_block
		(title "m-2 — Lightning_M.2_BRD.brd")
		(comment 1 "Lightning (Wiwynn / Facebook NVMe JBOF) / footprints 77-78 of 157")
	)
	(layers
		(0 "F.Cu" signal "TOP")
		(4 "In1.Cu" signal "L2GND")
		(6 "In2.Cu" signal "L3")
		(8 "In3.Cu" signal "L4GND")
		(10 "In4.Cu" signal "L5GND")
		(12 "In5.Cu" signal "L6")
		(14 "In6.Cu" signal "L7GND")
		(2 "B.Cu" signal "BOTTOM")
		(9 "F.Adhes" user "F.Adhesive")
		(11 "B.Adhes" user "B.Adhesive")
		(13 "F.Paste" user "Package Geometry/Pastemask Top")
		(15 "B.Paste" user "Package Geometry/Pastemask Bottom")
		(5 "F.SilkS" user "Ref Des/Silkscreen Top")
		(7 "B.SilkS" user "Ref Des/Silkscreen Bottom")
		(1 "F.Mask" user "Board Geometry/Soldermask Top")
		(3 "B.Mask" user "Board Geometry/Soldermask Bottom")
		(17 "Dwgs.User" user "User.Drawings")
		(19 "Cmts.User" user "User.Comments")
		(21 "Eco1.User" user "User.Eco1")
		(23 "Eco2.User" user "User.Eco2")
		(25 "Edge.Cuts" user "Board Geometry/Outline")
		(27 "Margin" user)
		(31 "F.CrtYd" user "Package Geometry/Place Bound Top")
		(29 "B.CrtYd" user "Package Geometry/Place Bound Bottom")
		(35 "F.Fab" user "Ref Des/Assembly Top")
		(33 "B.Fab" user "Ref Des/Assembly Bottom")
	)
	(footprint ""
		(layer "F.Cu")
		(at 49.784 -85.979 180)
		(property "Reference" "PC30"
			(at 0 0 180)
			(layer "F.SilkS")
			(hide yes)
			(effects
				(font
					(size 1.27 1.27)
				)
			)
		)
		(property "Value" "SC2K2P50V3KX-GP"
			(at 0 -2.8194 180)
			(unlocked yes)
			(layer "F.Fab")
			(hide yes)
			(effects
				(font
					(size 1.016 1.016)
					(thickness 0.1524)
				)
			)
		)
		(property "Device Type" "C603"
			(at 0 -4.3434 180)
			(unlocked yes)
			(layer "F.Fab")
			(hide yes)
			(effects
				(font
					(size 1.016 1.016)
					(thickness 0.1524)
				)
			)
		)
		(duplicate_pad_numbers_are_jumpers no)
		(fp_line
			(start 0.508 0)
			(end -0.508 0)
			(stroke
				(width 0.2032)
				(type default)
			)
			(layer "F.SilkS")
		)
		(fp_rect
			(start -0.5842 1.3335)
			(end 0.5842 -1.3335)
			(stroke
				(width 0)
				(type default)
			)
			(fill no)
			(layer "F.CrtYd")
		)
		(fp_rect
			(start -0.5842 1.3335)
			(end 0.5842 -1.3335)
			(stroke
				(width 0)
				(type default)
			)
			(fill no)
			(layer "F.Fab")
		)
		(pad "1" smd custom
			(at 0 -0.762 180)
			(size 0.2159 0.2159)
			(layers "F.Cu" "F.Mask" "F.Paste")
			(net "P3V3_DEV_LL")
			(options
				(clearance outline)
				(anchor circle)
			)
			(primitives
				(gr_poly
					(pts
						(arc
							(start -0.3302 -0.4318)
							(mid -0.402042 -0.402042)
							(end -0.4318 -0.3302)
						)
						(arc
							(start -0.4318 0.3302)
							(mid -0.402042 0.402042)
							(end -0.3302 0.4318)
						)
						(arc
							(start 0.3302 0.4318)
							(mid 0.402042 0.402042)
							(end 0.4318 0.3302)
						)
						(arc
							(start 0.4318 -0.3302)
							(mid 0.402042 -0.402042)
							(end 0.3302 -0.4318)
						)
					)
					(width 0)
					(fill yes)
				)
			)
		)
		(pad "2" smd custom
			(at 0 0.762 180)
			(size 0.2159 0.2159)
			(layers "F.Cu" "F.Mask" "F.Paste")
			(net "P3V3_DEV_SNB")
			(options
				(clearance outline)
				(anchor circle)
			)
			(primitives
				(gr_poly
					(pts
						(arc
							(start -0.3302 -0.4318)
							(mid -0.402042 -0.402042)
							(end -0.4318 -0.3302)
						)
						(arc
							(start -0.4318 0.3302)
							(mid -0.402042 0.402042)
							(end -0.3302 0.4318)
						)
						(arc
							(start 0.3302 0.4318)
							(mid 0.402042 0.402042)
							(end 0.4318 0.3302)
						)
						(arc
							(start 0.4318 -0.3302)
							(mid 0.402042 -0.402042)
							(end 0.3302 -0.4318)
						)
					)
					(width 0)
					(fill yes)
				)
			)
		)
	)
	(footprint ""
		(layer "F.Cu")
		(at 67.449954 -26.439876 -90)
		(property "Reference" "SSD_B1"
			(at 0 0 270)
			(layer "F.SilkS")
			(hide yes)
			(effects
				(font
					(size 1.27 1.27)
				)
			)
		)
		(property "Value" "SKT-MINI75P-11-GP"
			(at 12.6619 2.2733 270)
			(unlocked yes)
			(layer "F.Fab")
			(hide yes)
			(effects
				(font
					(size 1.016 1.016)
					(thickness 0.1524)
				)
			)
		)
		(property "Device Type" "MDT580M01001"
			(at 12.6619 0.7493 270)
			(unlocked yes)
			(layer "F.Fab")
			(hide yes)
			(effects
				(font
					(size 1.016 1.016)
					(thickness 0.1524)
				)
			)
		)
		(duplicate_pad_numbers_are_jumpers no)
		(fp_line
			(start -11.2522 3.302)
			(end -11.2522 -6.2992)
			(stroke
				(width 0.1524)
				(type default)
			)
			(layer "F.SilkS")
		)
		(fp_line
			(start 11.2522 3.302)
			(end -11.2522 3.302)
			(stroke
				(width 0.1524)
				(type default)
			)
			(layer "F.SilkS")
		)
		(fp_line
			(start -11.2522 -6.2992)
			(end 11.2522 -6.2992)
			(stroke
				(width 0.1524)
				(type default)
			)
			(layer "F.SilkS")
		)
		(fp_line
			(start 11.2522 -6.2992)
			(end 11.2522 3.302)
			(stroke
				(width 0.1524)
				(type default)
			)
			(layer "F.SilkS")
		)
		(fp_line
			(start -9.525 -6.3881)
			(end -9.017 -6.3881)
			(stroke
				(width 0.3302)
				(type default)
			)
			(layer "F.SilkS")
		)
		(fp_poly
			(pts
				(xy -9.273794 -6.315202) (xy -8.841994 -6.747002) (xy -9.705594 -6.747002)
			)
			(stroke
				(width 0)
				(type default)
			)
			(fill yes)
			(layer "F.SilkS")
		)
		(fp_rect
			(start -10.9982 2.8448)
			(end 10.9982 -5.6896)
			(stroke
				(width 0)
				(type default)
			)
			(fill no)
			(layer "F.CrtYd")
		)
		(fp_poly
			(pts
				(xy -11.5062 3.556) (xy -11.5062 -6.5532) (xy 11.5062 -6.5532) (xy 11.5062 -0.00635) (xy 10.9982 -0.00635)
				(xy 10.9982 -5.6896) (xy -10.9982 -5.6896) (xy -10.9982 2.8448) (xy 10.9982 2.8448) (xy 10.9982 0.00635)
				(xy 11.5062 0.00635) (xy 11.5062 3.556)
			)
			(stroke
				(width 0)
				(type default)
			)
			(fill no)
			(layer "F.CrtYd")
		)
		(fp_rect
			(start -11.5062 3.556)
			(end 11.5062 -6.5532)
			(stroke
				(width 0)
				(type default)
			)
			(fill no)
			(layer "F.Fab")
		)
		(pad "" np_thru_hole circle
			(at -9.99998 0 270)
			(size 0.254 0.254)
			(drill 1.1176)
			(layers "*.Cu" "*.Mask")
			(clearance 0.7874)
			(thermal_gap 0.7874)
		)
		(pad "" np_thru_hole circle
			(at 9.99998 0 270)
			(size 0.254 0.254)
			(drill 1.6002)
			(layers "*.Cu" "*.Mask")
			(clearance 1.0287)
			(thermal_gap 1.0287)
		)
		(pad "1" smd rect
			(at -9.249918 -5.275072 270)
			(size 0.3048 1.5494)
			(layers "F.Cu" "F.Mask" "F.Paste")
			(net "Z50_SSD_B_PRESENT_R#")
		)
		(pad "2" smd rect
			(at -8.999982 2.275078 270)
			(size 0.3048 1.5494)
			(layers "F.Cu" "F.Mask" "F.Paste")
			(net "P3V3_PWR")
		)
		(pad "3" smd rect
			(at -8.750046 -5.275072 270)
			(size 0.3048 1.5494)
			(layers "F.Cu" "F.Mask" "F.Paste")
			(net "GND")
		)
		(pad "4" smd rect
			(at -8.50011 2.275078 270)
			(size 0.3048 1.5494)
			(layers "F.Cu" "F.Mask" "F.Paste")
			(net "P3V3_PWR")
		)
		(pad "5" smd rect
			(at -8.24992 -5.275072 270)
			(size 0.3048 1.5494)
			(layers "F.Cu" "F.Mask" "F.Paste")
			(net "Net_117")
		)
		(pad "6" smd rect
			(at -7.999984 2.275078 270)
			(size 0.3048 1.5494)
			(layers "F.Cu" "F.Mask" "F.Paste")
			(net "Net_124")
		)
		(pad "7" smd rect
			(at -7.750048 -5.275072 270)
			(size 0.3048 1.5494)
			(layers "F.Cu" "F.Mask" "F.Paste")
			(net "Net_118")
		)
		(pad "8" smd rect
			(at -7.500112 2.275078 270)
			(size 0.3048 1.5494)
			(layers "F.Cu" "F.Mask" "F.Paste")
			(net "Net_125")
		)
		(pad "9" smd rect
			(at -7.249922 -5.275072 270)
			(size 0.3048 1.5494)
			(layers "F.Cu" "F.Mask" "F.Paste")
			(net "GND")
		)
		(pad "10" smd rect
			(at -6.999986 2.275078 270)
			(size 0.3048 1.5494)
			(layers "F.Cu" "F.Mask" "F.Paste")
			(net "Z50_SSD_B_R_ACT#")
		)
		(pad "11" smd rect
			(at -6.75005 -5.275072 270)
			(size 0.3048 1.5494)
			(layers "F.Cu" "F.Mask" "F.Paste")
			(net "Net_119")
		)
		(pad "12" smd rect
			(at -6.500114 2.275078 270)
			(size 0.3048 1.5494)
			(layers "F.Cu" "F.Mask" "F.Paste")
			(net "P3V3_PWR")
		)
		(pad "13" smd rect
			(at -6.249924 -5.275072 270)
			(size 0.3048 1.5494)
			(layers "F.Cu" "F.Mask" "F.Paste")
			(net "Net_120")
		)
		(pad "14" smd rect
			(at -5.999988 2.275078 270)
			(size 0.3048 1.5494)
			(layers "F.Cu" "F.Mask" "F.Paste")
			(net "P3V3_PWR")
		)
		(pad "15" smd rect
			(at -5.750052 -5.275072 270)
			(size 0.3048 1.5494)
			(layers "F.Cu" "F.Mask" "F.Paste")
			(net "GND")
		)
		(pad "16" smd rect
			(at -5.500116 2.275078 270)
			(size 0.3048 1.5494)
			(layers "F.Cu" "F.Mask" "F.Paste")
			(net "P3V3_PWR")
		)
		(pad "17" smd rect
			(at -5.249926 -5.275072 270)
			(size 0.3048 1.5494)
			(layers "F.Cu" "F.Mask" "F.Paste")
			(net "Net_121")
		)
		(pad "18" smd rect
			(at -4.99999 2.275078 270)
			(size 0.3048 1.5494)
			(layers "F.Cu" "F.Mask" "F.Paste")
			(net "P3V3_PWR")
		)
		(pad "19" smd rect
			(at -4.750054 -5.275072 270)
			(size 0.3048 1.5494)
			(layers "F.Cu" "F.Mask" "F.Paste")
			(net "Net_122")
		)
		(pad "20" smd rect
			(at -4.500118 2.275078 270)
			(size 0.3048 1.5494)
			(layers "F.Cu" "F.Mask" "F.Paste")
			(net "Net_126")
		)
		(pad "21" smd rect
			(at -4.249928 -5.275072 270)
			(size 0.3048 1.5494)
			(layers "F.Cu" "F.Mask" "F.Paste")
			(net "GND")
		)
		(pad "22" smd rect
			(at -3.999992 2.275078 270)
			(size 0.3048 1.5494)
			(layers "F.Cu" "F.Mask" "F.Paste")
			(net "Net_127")
		)
		(pad "23" smd rect
			(at -3.750056 -5.275072 270)
			(size 0.3048 1.5494)
			(layers "F.Cu" "F.Mask" "F.Paste")
			(net "Net_123")
		)
		(pad "24" smd rect
			(at -3.50012 2.275078 270)
			(size 0.3048 1.5494)
			(layers "F.Cu" "F.Mask" "F.Paste")
			(net "Net_107")
		)
		(pad "25" smd rect
			(at -3.24993 -5.275072 270)
			(size 0.3048 1.5494)
			(layers "F.Cu" "F.Mask" "F.Paste")
			(net "Net_106")
		)
		(pad "26" smd rect
			(at -2.999994 2.275078 270)
			(size 0.3048 1.5494)
			(layers "F.Cu" "F.Mask" "F.Paste")
			(net "Net_108")
		)
		(pad "27" smd rect
			(at -2.750058 -5.275072 270)
			(size 0.3048 1.5494)
			(layers "F.Cu" "F.Mask" "F.Paste")
			(net "GND")
		)
		(pad "28" smd rect
			(at -2.500122 2.275078 270)
			(size 0.3048 1.5494)
			(layers "F.Cu" "F.Mask" "F.Paste")
			(net "Net_109")
		)
		(pad "29" smd rect
			(at -2.249932 -5.275072 270)
			(size 0.3048 1.5494)
			(layers "F.Cu" "F.Mask" "F.Paste")
			(net "D85_PCIE_B_RX0_N")
		)
		(pad "30" smd rect
			(at -1.999996 2.275078 270)
			(size 0.3048 1.5494)
			(layers "F.Cu" "F.Mask" "F.Paste")
			(net "Net_110")
		)
		(pad "31" smd rect
			(at -1.75006 -5.275072 270)
			(size 0.3048 1.5494)
			(layers "F.Cu" "F.Mask" "F.Paste")
			(net "D85_PCIE_B_RX0_P")
		)
		(pad "32" smd rect
			(at -1.500124 2.275078 270)
			(size 0.3048 1.5494)
			(layers "F.Cu" "F.Mask" "F.Paste")
			(net "Net_111")
		)
		(pad "33" smd rect
			(at -1.249934 -5.275072 270)
			(size 0.3048 1.5494)
			(layers "F.Cu" "F.Mask" "F.Paste")
			(net "GND")
		)
		(pad "34" smd rect
			(at -0.999998 2.275078 270)
			(size 0.3048 1.5494)
			(layers "F.Cu" "F.Mask" "F.Paste")
			(net "Net_112")
		)
		(pad "35" smd rect
			(at -0.750062 -5.275072 270)
			(size 0.3048 1.5494)
			(layers "F.Cu" "F.Mask" "F.Paste")
			(net "D85_PCIE_B_TX0_P")
		)
		(pad "36" smd rect
			(at -0.500126 2.275078 270)
			(size 0.3048 1.5494)
			(layers "F.Cu" "F.Mask" "F.Paste")
			(net "Net_113")
		)
		(pad "37" smd rect
			(at -0.249936 -5.275072 270)
			(size 0.3048 1.5494)
			(layers "F.Cu" "F.Mask" "F.Paste")
			(net "D85_PCIE_B_TX0_N")
		)
		(pad "38" smd rect
			(at 0 2.275078 270)
			(size 0.3048 1.5494)
			(layers "F.Cu" "F.Mask" "F.Paste")
			(net "Net_114")
		)
		(pad "39" smd rect
			(at 0.249936 -5.275072 270)
			(size 0.3048 1.5494)
			(layers "F.Cu" "F.Mask" "F.Paste")
			(net "GND")
		)
		(pad "40" smd rect
			(at 0.500126 2.275078 270)
			(size 0.3048 1.5494)
			(layers "F.Cu" "F.Mask" "F.Paste")
			(net "Z50_SSD_B1_SMB_CLK")
		)
		(pad "41" smd rect
			(at 0.750062 -5.275072 270)
			(size 0.3048 1.5494)
			(layers "F.Cu" "F.Mask" "F.Paste")
			(net "D85_PCIE_B_RX1_N")
		)
		(pad "42" smd rect
			(at 0.999998 2.275078 270)
			(size 0.3048 1.5494)
			(layers "F.Cu" "F.Mask" "F.Paste")
			(net "Z50_SSD_B1_SMB_DATA")
		)
		(pad "43" smd rect
			(at 1.249934 -5.275072 270)
			(size 0.3048 1.5494)
			(layers "F.Cu" "F.Mask" "F.Paste")
			(net "D85_PCIE_B_RX1_P")
		)
		(pad "44" smd rect
			(at 1.500124 2.275078 270)
			(size 0.3048 1.5494)
			(layers "F.Cu" "F.Mask" "F.Paste")
			(net "Z50_SSD_B1_ALERT#")
		)
		(pad "45" smd rect
			(at 1.75006 -5.275072 270)
			(size 0.3048 1.5494)
			(layers "F.Cu" "F.Mask" "F.Paste")
			(net "GND")
		)
		(pad "46" smd rect
			(at 1.999996 2.275078 270)
			(size 0.3048 1.5494)
			(layers "F.Cu" "F.Mask" "F.Paste")
			(net "Net_115")
		)
		(pad "47" smd rect
			(at 2.249932 -5.275072 270)
			(size 0.3048 1.5494)
			(layers "F.Cu" "F.Mask" "F.Paste")
			(net "D85_PCIE_B_TX1_P")
		)
		(pad "48" smd rect
			(at 2.500122 2.275078 270)
			(size 0.3048 1.5494)
			(layers "F.Cu" "F.Mask" "F.Paste")
			(net "Net_116")
		)
		(pad "49" smd rect
			(at 2.750058 -5.275072 270)
			(size 0.3048 1.5494)
			(layers "F.Cu" "F.Mask" "F.Paste")
			(net "D85_PCIE_B_TX1_N")
		)
		(pad "50" smd rect
			(at 2.999994 2.275078 270)
			(size 0.3048 1.5494)
			(layers "F.Cu" "F.Mask" "F.Paste")
			(net "Z50_DEV_RST#")
		)
		(pad "51" smd rect
			(at 3.24993 -5.275072 270)
			(size 0.3048 1.5494)
			(layers "F.Cu" "F.Mask" "F.Paste")
			(net "GND")
		)
		(pad "52" smd rect
			(at 3.50012 2.275078 270)
			(size 0.3048 1.5494)
			(layers "F.Cu" "F.Mask" "F.Paste")
			(net "Z50_SSD_B1_CLKREQ#")
		)
		(pad "53" smd rect
			(at 3.750056 -5.275072 270)
			(size 0.3048 1.5494)
			(layers "F.Cu" "F.Mask" "F.Paste")
			(net "D85_PCIE_B_REFCLK_N")
		)
		(pad "54" smd rect
			(at 3.999992 2.275078 270)
			(size 0.3048 1.5494)
			(layers "F.Cu" "F.Mask" "F.Paste")
			(net "Net_103")
		)
		(pad "55" smd rect
			(at 4.249928 -5.275072 270)
			(size 0.3048 1.5494)
			(layers "F.Cu" "F.Mask" "F.Paste")
			(net "D85_PCIE_B_REFCLK_P")
		)
		(pad "56" smd rect
			(at 4.500118 2.275078 270)
			(size 0.3048 1.5494)
			(layers "F.Cu" "F.Mask" "F.Paste")
			(net "SSD_B1_MFG_DATA_TP")
		)
		(pad "57" smd rect
			(at 4.750054 -5.275072 270)
			(size 0.3048 1.5494)
			(layers "F.Cu" "F.Mask" "F.Paste")
			(net "GND")
		)
		(pad "58" smd rect
			(at 4.99999 2.275078 270)
			(size 0.3048 1.5494)
			(layers "F.Cu" "F.Mask" "F.Paste")
			(net "SSD_B1_MFG_CLK_TP")
		)
		(pad "67" smd rect
			(at 7.249922 -5.275072 270)
			(size 0.3048 1.5494)
			(layers "F.Cu" "F.Mask" "F.Paste")
			(net "Net_101")
		)
		(pad "68" smd rect
			(at 7.500112 2.275078 270)
			(size 0.3048 1.5494)
			(layers "F.Cu" "F.Mask" "F.Paste")
			(net "Net_104")
		)
		(pad "69" smd rect
			(at 7.750048 -5.275072 270)
			(size 0.3048 1.5494)
			(layers "F.Cu" "F.Mask" "F.Paste")
			(net "Net_102")
		)
		(pad "70" smd rect
			(at 7.999984 2.275078 270)
			(size 0.3048 1.5494)
			(layers "F.Cu" "F.Mask" "F.Paste")
			(net "P3V3_PWR")
		)
		(pad "71" smd rect
			(at 8.24992 -5.275072 270)
			(size 0.3048 1.5494)
			(layers "F.Cu" "F.Mask" "F.Paste")
			(net "GND")
		)
		(pad "72" smd rect
			(at 8.50011 2.275078 270)
			(size 0.3048 1.5494)
			(layers "F.Cu" "F.Mask" "F.Paste")
			(net "P3V3_PWR")
		)
		(pad "73" smd rect
			(at 8.750046 -5.275072 270)
			(size 0.3048 1.5494)
			(layers "F.Cu" "F.Mask" "F.Paste")
			(net "GND")
		)
		(pad "74" smd rect
			(at 8.999982 2.275078 270)
			(size 0.3048 1.5494)
			(layers "F.Cu" "F.Mask" "F.Paste")
			(net "P3V3_PWR")
		)
		(pad "75" smd rect
			(at 9.249918 -5.275072 270)
			(size 0.3048 1.5494)
			(layers "F.Cu" "F.Mask" "F.Paste")
			(net "GND")
		)
		(pad "76" smd rect
			(at -10.349992 -4.500118 270)
			(size 1.1938 2.7432)
			(layers "F.Cu" "F.Mask" "F.Paste")
			(net "GND")
		)
		(pad "77" smd rect
			(at 10.349992 -4.500118 270)
			(size 1.1938 2.7432)
			(layers "F.Cu" "F.Mask" "F.Paste")
			(net "GND")
		)
		(zone
			(layer "F.Cu")
			(hatch none 0.5)
			(connect_pads
				(clearance 0)
			)
			(min_thickness 0.25)
			(keepout
				(tracks allowed)
				(vias not_allowed)
				(pads allowed)
				(copperpour not_allowed)
				(footprints allowed)
			)
			(placement
				(enabled no)
				(sheetname "")
			)
			(fill
				(thermal_gap 0.5)
				(thermal_bridge_width 0.5)
				(island_removal_mode 0)
			)
			(polygon
				(pts
					(xy 65.949576 -35.592258) (xy 65.949576 -21.287486) (xy 66.457576 -21.287486) (xy 66.457576 -35.592258)
				)
			)
		)
		(zone
			(layer "F.Cu")
			(hatch none 0.5)
			(connect_pads
				(clearance 0)
			)
			(min_thickness 0.25)
			(keepout
				(tracks allowed)
				(vias not_allowed)
				(pads allowed)
				(copperpour not_allowed)
				(footprints allowed)
			)
			(placement
				(enabled no)
				(sheetname "")
			)
			(fill
				(thermal_gap 0.5)
				(thermal_bridge_width 0.5)
				(island_removal_mode 0)
			)
			(polygon
				(pts
					(xy 65.949576 -19.092164) (xy 65.949576 -17.287494) (xy 66.457576 -17.287494) (xy 66.457576 -19.092164)
				)
			)
		)
		(zone
			(layer "F.Cu")
			(hatch none 0.5)
			(connect_pads
				(clearance 0)
			)
			(min_thickness 0.25)
			(keepout
				(tracks allowed)
				(vias not_allowed)
				(pads allowed)
				(copperpour not_allowed)
				(footprints allowed)
			)
			(placement
				(enabled no)
				(sheetname "")
			)
			(fill
				(thermal_gap 0.5)
				(thermal_bridge_width 0.5)
				(island_removal_mode 0)
			)
			(polygon
				(pts
					(xy 71.442326 -35.842194) (xy 71.442326 -21.537422) (xy 71.950326 -21.537422) (xy 71.950326 -35.842194)
				)
			)
		)
		(zone
			(layer "F.Cu")
			(hatch none 0.5)
			(connect_pads
				(clearance 0)
			)
			(min_thickness 0.25)
			(keepout
				(tracks allowed)
				(vias not_allowed)
				(pads allowed)
				(copperpour not_allowed)
				(footprints allowed)
			)
			(placement
				(enabled no)
				(sheetname "")
			)
			(fill
				(thermal_gap 0.5)
				(thermal_bridge_width 0.5)
				(island_removal_mode 0)
			)
			(polygon
				(pts
					(xy 71.442326 -19.342354) (xy 71.442326 -17.037558) (xy 71.950326 -17.037558) (xy 71.950326 -19.342354)
				)
			)
		)
		(zone
			(layers "F.Cu" "B.Cu" "In1.Cu" "In2.Cu" "In3.Cu" "In4.Cu" "In5.Cu" "In6.Cu")
			(hatch none 0.5)
			(connect_pads
				(clearance 0)
			)
			(min_thickness 0.25)
			(keepout
				(tracks not_allowed)
				(vias allowed)
				(pads allowed)
				(copperpour not_allowed)
				(footprints allowed)
			)
			(placement
				(enabled no)
				(sheetname "")
			)
			(fill
				(thermal_gap 0.5)
				(thermal_bridge_width 0.5)
				(island_removal_mode 0)
			)
			(polygon
				(pts
					(arc
						(start 68.313554 -36.439856)
						(mid 66.586354 -36.439856)
						(end 68.313554 -36.439856)
					)
				)
			)
		)
		(zone
			(layers "F.Cu" "B.Cu" "In1.Cu" "In2.Cu" "In3.Cu" "In4.Cu" "In5.Cu" "In6.Cu")
			(hatch none 0.5)
			(connect_pads
				(clearance 0)
			)
			(min_thickness 0.25)
			(keepout
				(tracks not_allowed)
				(vias allowed)
				(pads allowed)
				(copperpour not_allowed)
				(footprints allowed)
			)
			(placement
				(enabled no)
				(sheetname "")
			)
			(fill
				(thermal_gap 0.5)
				(thermal_bridge_width 0.5)
				(island_removal_mode 0)
			)
			(polygon
				(pts
					(arc
						(start 68.554854 -16.439896)
						(mid 66.345054 -16.439896)
						(end 68.554854 -16.439896)
					)
				)
			)
		)
	)
)
